(kicad_pcb
	(version 20260206)
	(generator "pcbnew")
	(generator_version "10.0")
	(general
		(thickness 1.6)
		(legacy_teardrops no)
	)
	(paper "A4")
	(title_block
		(title "Bryce Canyon_IOM_IOC_16318-2_OCP.brd")
		(comment 1 "Bryce Canyon / footprints 830-835 of 1605")
	)
	(layers
		(0 "F.Cu" signal "TOP")
		(4 "In1.Cu" signal "L2GND")
		(6 "In2.Cu" signal "L3")
		(8 "In3.Cu" signal "L4VCC")
		(10 "In4.Cu" signal "L5VCC")
		(12 "In5.Cu" signal "L6")
		(14 "In6.Cu" signal "L7GND")
		(2 "B.Cu" signal "BOTTOM")
		(9 "F.Adhes" user "F.Adhesive")
		(11 "B.Adhes" user "B.Adhesive")
		(13 "F.Paste" user "Package Geometry/Pastemask Top")
		(15 "B.Paste" user "Package Geometry/Pastemask Bottom")
		(5 "F.SilkS" user "Ref Des/Silkscreen Top")
		(7 "B.SilkS" user "Ref Des/Silkscreen Bottom")
		(1 "F.Mask" user "Board Geometry/Soldermask Top")
		(3 "B.Mask" user "Board Geometry/Soldermask Bottom")
		(17 "Dwgs.User" user "User.Drawings")
		(19 "Cmts.User" user "User.Comments")
		(21 "Eco1.User" user "User.Eco1")
		(23 "Eco2.User" user "User.Eco2")
		(25 "Edge.Cuts" user "Board Geometry/Outline")
		(27 "Margin" user)
		(31 "F.CrtYd" user "Package Geometry/Place Bound Top")
		(29 "B.CrtYd" user "Package Geometry/Place Bound Bottom")
		(35 "F.Fab" user "Ref Des/Assembly Top")
		(33 "B.Fab" user "Ref Des/Assembly Bottom")
	)
	(footprint ""
		(layer "F.Cu")
		(at 194.00012 -6.199886)
		(property "Reference" "LED2"
			(at 0 0 0)
			(layer "F.SilkS")
			(hide yes)
			(effects
				(font
					(size 1.27 1.27)
				)
			)
		)
		(property "Value" "LED-BY-14-GP"
			(at -4.7752 -2.1844 0)
			(unlocked yes)
			(layer "F.Fab")
			(hide yes)
			(effects
				(font
					(size 1.016 1.016)
					(thickness 0.1524)
				)
			)
		)
		(property "Device Type" "LED-100-3PH206"
			(at -4.7752 -3.7084 0)
			(unlocked yes)
			(layer "F.Fab")
			(hide yes)
			(effects
				(font
					(size 1.016 1.016)
					(thickness 0.1524)
				)
			)
		)
		(duplicate_pad_numbers_are_jumpers no)
		(fp_line
			(start -3.7592 -1.524)
			(end 3.7592 -1.524)
			(stroke
				(width 0.1524)
				(type default)
			)
			(layer "F.SilkS")
		)
		(fp_line
			(start -3.7592 8.0264)
			(end -3.7592 -1.524)
			(stroke
				(width 0.1524)
				(type default)
			)
			(layer "F.SilkS")
		)
		(fp_line
			(start -1.75387 1.04394)
			(end -1.75387 3.63474)
			(stroke
				(width 0.1524)
				(type default)
			)
			(layer "F.SilkS")
		)
		(fp_line
			(start -1.75387 2.33934)
			(end -3.45567 2.33934)
			(stroke
				(width 0.1524)
				(type default)
			)
			(layer "F.SilkS")
		)
		(fp_line
			(start -1.75387 3.63474)
			(end -0.45847 2.33934)
			(stroke
				(width 0.1524)
				(type default)
			)
			(layer "F.SilkS")
		)
		(fp_line
			(start -0.45847 2.33934)
			(end -1.75387 1.04394)
			(stroke
				(width 0.1524)
				(type default)
			)
			(layer "F.SilkS")
		)
		(fp_line
			(start -0.45847 2.33934)
			(end 0.58293 2.33934)
			(stroke
				(width 0.1524)
				(type default)
			)
			(layer "F.SilkS")
		)
		(fp_line
			(start -0.45847 3.05054)
			(end -0.45847 1.42494)
			(stroke
				(width 0.1524)
				(type default)
			)
			(layer "F.SilkS")
		)
		(fp_line
			(start 0.58293 2.33934)
			(end 1.87833 1.04394)
			(stroke
				(width 0.1524)
				(type default)
			)
			(layer "F.SilkS")
		)
		(fp_line
			(start 0.58293 3.05054)
			(end 0.58293 1.42494)
			(stroke
				(width 0.1524)
				(type default)
			)
			(layer "F.SilkS")
		)
		(fp_line
			(start 1.87833 1.04394)
			(end 1.87833 3.63474)
			(stroke
				(width 0.1524)
				(type default)
			)
			(layer "F.SilkS")
		)
		(fp_line
			(start 1.87833 2.33934)
			(end 2.81813 2.33934)
			(stroke
				(width 0.1524)
				(type default)
			)
			(layer "F.SilkS")
		)
		(fp_line
			(start 1.87833 3.63474)
			(end 0.58293 2.33934)
			(stroke
				(width 0.1524)
				(type default)
			)
			(layer "F.SilkS")
		)
		(fp_line
			(start 3.7592 -1.524)
			(end 3.7592 8.0264)
			(stroke
				(width 0.1524)
				(type default)
			)
			(layer "F.SilkS")
		)
		(fp_line
			(start 3.7592 8.0264)
			(end -3.7592 8.0264)
			(stroke
				(width 0.1524)
				(type default)
			)
			(layer "F.SilkS")
		)
		(fp_circle
			(center -2.54 0)
			(end -1.5494 0)
			(stroke
				(width 0.3048)
				(type default)
			)
			(fill no)
			(layer "F.SilkS")
		)
		(fp_circle
			(center 0 0)
			(end 0.9906 0)
			(stroke
				(width 0.3048)
				(type default)
			)
			(fill no)
			(layer "F.SilkS")
		)
		(fp_circle
			(center 2.54 0)
			(end 3.5306 0)
			(stroke
				(width 0.3048)
				(type default)
			)
			(fill no)
			(layer "F.SilkS")
		)
		(fp_rect
			(start -3.5052 7.7724)
			(end 3.5052 -1.27)
			(stroke
				(width 0)
				(type default)
			)
			(fill no)
			(layer "F.CrtYd")
		)
		(fp_poly
			(pts
				(xy -4.0132 8.2804) (xy -4.0132 -1.778) (xy -3.5052 -1.778) (xy -3.5052 7.7724) (xy 3.5052 7.7724)
				(xy 3.5052 -1.27) (xy -3.50012 -1.27) (xy -3.50012 -1.778) (xy 4.0132 -1.778) (xy 4.0132 8.2804)
			)
			(stroke
				(width 0)
				(type default)
			)
			(fill no)
			(layer "F.CrtYd")
		)
		(fp_rect
			(start -4.0132 8.2804)
			(end 4.0132 -1.778)
			(stroke
				(width 0)
				(type default)
			)
			(fill no)
			(layer "F.Fab")
		)
		(pad "1" thru_hole circle
			(at -2.54 0)
			(size 1.27 1.27)
			(drill 0.889)
			(layers "*.Cu" "*.Mask")
			(remove_unused_layers no)
			(net "EXT1_LED_BLUE")
			(clearance 0.1651)
			(thermal_gap 0.1651)
		)
		(pad "2" thru_hole circle
			(at 0 0)
			(size 1.27 1.27)
			(drill 0.889)
			(layers "*.Cu" "*.Mask")
			(remove_unused_layers no)
			(net "GND")
			(clearance 0.1651)
			(thermal_gap 0.1651)
		)
		(pad "3" thru_hole circle
			(at 2.54 0)
			(size 1.27 1.27)
			(drill 0.889)
			(layers "*.Cu" "*.Mask")
			(remove_unused_layers no)
			(net "EXT1_LED_YELLOW")
			(clearance 0.1651)
			(thermal_gap 0.1651)
		)
	)
	(footprint ""
		(layer "F.Cu")
		(at 215.9 -79.248 -45)
		(property "Reference" "VIA41"
			(at 0 0 315)
			(layer "F.SilkS")
			(hide yes)
			(effects
				(font
					(size 1.27 1.27)
				)
			)
		)
		(property "Value" "100OHM-8L-1D6MM-L18L16-GP"
			(at -3.721059 -4.508373 315)
			(unlocked yes)
			(layer "F.Fab")
			(hide yes)
			(effects
				(font
					(size 1.016 1.016)
					(thickness 0.1524)
				)
			)
		)
		(property "Device Type" "VIA-PCIE-4P-394076"
			(at -3.721059 -6.032502 315)
			(unlocked yes)
			(layer "F.Fab")
			(hide yes)
			(effects
				(font
					(size 1.016 1.016)
					(thickness 0.1524)
				)
			)
		)
		(duplicate_pad_numbers_are_jumpers no)
		(fp_poly
			(pts
				(xy -1.968472 -0.380877) (xy 1.968528 -0.380878) (xy 1.968527 0.381122) (xy -1.968472 0.381122)
			)
			(stroke
				(width 0)
				(type default)
			)
			(fill no)
			(layer "F.CrtYd")
		)
		(fp_poly
			(pts
				(xy -1.968472 -0.380877) (xy 1.968528 -0.380878) (xy 1.968527 0.381122) (xy -1.968472 0.381122)
			)
			(stroke
				(width 0)
				(type default)
			)
			(fill no)
			(layer "F.Fab")
		)
		(pad "1" thru_hole circle
			(at -1.5875 0 315)
			(size 0.508 0.508)
			(drill 0.254)
			(layers "*.Cu" "*.Mask")
			(remove_unused_layers no)
			(net "GND")
			(clearance 0.127)
			(thermal_gap 0.127)
		)
		(pad "2" thru_hole circle
			(at -0.571501 0 315)
			(size 0.508 0.508)
			(drill 0.254)
			(layers "*.Cu" "*.Mask")
			(remove_unused_layers no)
			(net "PHY_IOC_TO_CON_A_0_DP")
			(clearance 0.127)
			(thermal_gap 0.127)
		)
		(pad "3" thru_hole circle
			(at 0.571501 0 315)
			(size 0.508 0.508)
			(drill 0.254)
			(layers "*.Cu" "*.Mask")
			(remove_unused_layers no)
			(net "PHY_IOC_TO_CON_A_0_DN")
			(clearance 0.127)
			(thermal_gap 0.127)
		)
		(pad "4" thru_hole circle
			(at 1.5875 0 315)
			(size 0.508 0.508)
			(drill 0.254)
			(layers "*.Cu" "*.Mask")
			(remove_unused_layers no)
			(net "GND")
			(clearance 0.127)
			(thermal_gap 0.127)
		)
	)
	(footprint ""
		(layer "F.Cu")
		(at 98.9076 -152.9334 -90)
		(property "Reference" "R31"
			(at 0 0 270)
			(layer "F.SilkS")
			(hide yes)
			(effects
				(font
					(size 1.27 1.27)
				)
			)
		)
		(property "Value" "4K7R2F-GP"
			(at 0.064008 -3.993896 270)
			(unlocked yes)
			(layer "F.Fab")
			(hide yes)
			(effects
				(font
					(size 1.016 1.016)
					(thickness 0.1524)
				)
			)
		)
		(property "Device Type" "R402H16"
			(at 0.064008 -5.517896 270)
			(unlocked yes)
			(layer "F.Fab")
			(hide yes)
			(effects
				(font
					(size 1.016 1.016)
					(thickness 0.1524)
				)
			)
		)
		(duplicate_pad_numbers_are_jumpers no)
		(fp_line
			(start -0.508 -0.9398)
			(end -0.508 0.9398)
			(stroke
				(width 0.1524)
				(type default)
			)
			(layer "F.SilkS")
		)
		(fp_line
			(start 0.508 -0.9398)
			(end -0.508 -0.9398)
			(stroke
				(width 0.1524)
				(type default)
			)
			(layer "F.SilkS")
		)
		(fp_rect
			(start -0.508 0.9398)
			(end 0.508 -0.9398)
			(stroke
				(width 0)
				(type default)
			)
			(fill no)
			(layer "F.CrtYd")
		)
		(fp_rect
			(start -0.508 0.9398)
			(end 0.508 -0.9398)
			(stroke
				(width 0)
				(type default)
			)
			(fill no)
			(layer "F.Fab")
		)
		(pad "1" smd custom
			(at 0 -0.4445 270)
			(size 0.1397 0.1397)
			(layers "F.Cu" "F.Mask" "F.Paste")
			(net "P3V3_STBY")
			(options
				(clearance outline)
				(anchor circle)
			)
			(primitives
				(gr_poly
					(pts
						(arc
							(start -0.1778 -0.2794)
							(mid -0.249642 -0.249642)
							(end -0.2794 -0.1778)
						)
						(arc
							(start -0.2794 0.1778)
							(mid -0.249642 0.249642)
							(end -0.1778 0.2794)
						)
						(arc
							(start 0.1778 0.2794)
							(mid 0.249642 0.249642)
							(end 0.2794 0.1778)
						)
						(arc
							(start 0.2794 -0.1778)
							(mid 0.249642 -0.249642)
							(end 0.1778 -0.2794)
						)
					)
					(width 0)
					(fill yes)
				)
			)
		)
		(pad "2" smd custom
			(at 0 0.4445 270)
			(size 0.1397 0.1397)
			(layers "F.Cu" "F.Mask" "F.Paste")
			(net "USB_OCS_N4")
			(options
				(clearance outline)
				(anchor circle)
			)
			(primitives
				(gr_poly
					(pts
						(arc
							(start -0.1778 -0.2794)
							(mid -0.249642 -0.249642)
							(end -0.2794 -0.1778)
						)
						(arc
							(start -0.2794 0.1778)
							(mid -0.249642 0.249642)
							(end -0.1778 0.2794)
						)
						(arc
							(start 0.1778 0.2794)
							(mid 0.249642 0.249642)
							(end 0.2794 0.1778)
						)
						(arc
							(start 0.2794 -0.1778)
							(mid 0.249642 -0.249642)
							(end 0.1778 -0.2794)
						)
					)
					(width 0)
					(fill yes)
				)
			)
		)
	)
	(footprint ""
		(layer "F.Cu")
		(at 183.813704 -149.714966)
		(property "Reference" "C162"
			(at 0 0 0)
			(layer "F.SilkS")
			(hide yes)
			(effects
				(font
					(size 1.27 1.27)
				)
			)
		)
		(property "Value" "SC1KP50V2KX-1GP"
			(at 1.1811 -2.7051 0)
			(unlocked yes)
			(layer "F.Fab")
			(hide yes)
			(effects
				(font
					(size 1.016 1.016)
					(thickness 0.1524)
				)
			)
		)
		(property "Device Type" "C402H22"
			(at 1.181354 -4.2291 0)
			(unlocked yes)
			(layer "F.Fab")
			(hide yes)
			(effects
				(font
					(size 1.016 1.016)
					(thickness 0.1524)
				)
			)
		)
		(duplicate_pad_numbers_are_jumpers no)
		(fp_rect
			(start -0.4318 0.9525)
			(end 0.4318 -0.9525)
			(stroke
				(width 0)
				(type default)
			)
			(fill no)
			(layer "F.CrtYd")
		)
		(fp_rect
			(start -0.4318 0.9525)
			(end 0.4318 -0.9525)
			(stroke
				(width 0)
				(type default)
			)
			(fill no)
			(layer "F.Fab")
		)
		(pad "1" smd custom
			(at 0 -0.4445)
			(size 0.1524 0.1524)
			(layers "F.Cu" "F.Mask" "F.Paste")
			(net "P5V_LL_R")
			(options
				(clearance outline)
				(anchor circle)
			)
			(primitives
				(gr_poly
					(pts
						(arc
							(start 0.3048 -0.2032)
							(mid 0.275042 -0.275042)
							(end 0.2032 -0.3048)
						)
						(arc
							(start -0.2032 -0.3048)
							(mid -0.275042 -0.275042)
							(end -0.3048 -0.2032)
						)
						(arc
							(start -0.3048 0.2032)
							(mid -0.275042 0.275042)
							(end -0.2032 0.3048)
						)
						(arc
							(start 0.2032 0.3048)
							(mid 0.275042 0.275042)
							(end 0.3048 0.2032)
						)
					)
					(width 0)
					(fill yes)
				)
			)
		)
		(pad "2" smd custom
			(at 0 0.4445)
			(size 0.1524 0.1524)
			(layers "F.Cu" "F.Mask" "F.Paste")
			(net "P5V_VFB")
			(options
				(clearance outline)
				(anchor circle)
			)
			(primitives
				(gr_poly
					(pts
						(arc
							(start 0.3048 -0.2032)
							(mid 0.275042 -0.275042)
							(end 0.2032 -0.3048)
						)
						(arc
							(start -0.2032 -0.3048)
							(mid -0.275042 -0.275042)
							(end -0.3048 -0.2032)
						)
						(arc
							(start -0.3048 0.2032)
							(mid -0.275042 0.275042)
							(end -0.2032 0.3048)
						)
						(arc
							(start 0.2032 0.3048)
							(mid 0.275042 0.275042)
							(end 0.3048 0.2032)
						)
					)
					(width 0)
					(fill yes)
				)
			)
		)
	)
	(footprint ""
		(layer "F.Cu")
		(at 36.791646 -187.96381 -90)
		(property "Reference" "C180"
			(at 0 0 270)
			(layer "F.SilkS")
			(hide yes)
			(effects
				(font
					(size 1.27 1.27)
				)
			)
		)
		(property "Value" "SC2200P50V2KX-2GP"
			(at 1.1811 -2.7051 270)
			(unlocked yes)
			(layer "F.Fab")
			(hide yes)
			(effects
				(font
					(size 1.016 1.016)
					(thickness 0.1524)
				)
			)
		)
		(property "Device Type" "C402H22"
			(at 1.1811 -4.2291 270)
			(unlocked yes)
			(layer "F.Fab")
			(hide yes)
			(effects
				(font
					(size 1.016 1.016)
					(thickness 0.1524)
				)
			)
		)
		(duplicate_pad_numbers_are_jumpers no)
		(fp_rect
			(start -0.4318 0.9525)
			(end 0.4318 -0.9525)
			(stroke
				(width 0)
				(type default)
			)
			(fill no)
			(layer "F.CrtYd")
		)
		(fp_rect
			(start -0.4318 0.9525)
			(end 0.4318 -0.9525)
			(stroke
				(width 0)
				(type default)
			)
			(fill no)
			(layer "F.Fab")
		)
		(pad "1" smd custom
			(at 0 -0.4445 270)
			(size 0.1524 0.1524)
			(layers "F.Cu" "F.Mask" "F.Paste")
			(net "P3V3_STBY_LL")
			(options
				(clearance outline)
				(anchor circle)
			)
			(primitives
				(gr_poly
					(pts
						(arc
							(start 0.3048 -0.2032)
							(mid 0.275042 -0.275042)
							(end 0.2032 -0.3048)
						)
						(arc
							(start -0.2032 -0.3048)
							(mid -0.275042 -0.275042)
							(end -0.3048 -0.2032)
						)
						(arc
							(start -0.3048 0.2032)
							(mid -0.275042 0.275042)
							(end -0.2032 0.3048)
						)
						(arc
							(start 0.2032 0.3048)
							(mid 0.275042 0.275042)
							(end 0.3048 0.2032)
						)
					)
					(width 0)
					(fill yes)
				)
			)
		)
		(pad "2" smd custom
			(at 0 0.4445 270)
			(size 0.1524 0.1524)
			(layers "F.Cu" "F.Mask" "F.Paste")
			(net "P3V3_SNB")
			(options
				(clearance outline)
				(anchor circle)
			)
			(primitives
				(gr_poly
					(pts
						(arc
							(start 0.3048 -0.2032)
							(mid 0.275042 -0.275042)
							(end 0.2032 -0.3048)
						)
						(arc
							(start -0.2032 -0.3048)
							(mid -0.275042 -0.275042)
							(end -0.3048 -0.2032)
						)
						(arc
							(start -0.3048 0.2032)
							(mid -0.275042 0.275042)
							(end -0.2032 0.3048)
						)
						(arc
							(start 0.2032 0.3048)
							(mid 0.275042 0.275042)
							(end 0.3048 0.2032)
						)
					)
					(width 0)
					(fill yes)
				)
			)
		)
	)
	(footprint ""
		(layer "F.Cu")
		(at 173.519338 -61.06922 90)
		(property "Reference" "R582"
			(at 0 0 90)
			(layer "F.SilkS")
			(hide yes)
			(effects
				(font
					(size 1.27 1.27)
				)
			)
		)
		(property "Value" "2K2R2F-GP"
			(at 0.064008 -3.993896 90)
			(unlocked yes)
			(layer "F.Fab")
			(hide yes)
			(effects
				(font
					(size 1.016 1.016)
					(thickness 0.1524)
				)
			)
		)
		(property "Device Type" "R402H16"
			(at 0.064008 -5.517896 90)
			(unlocked yes)
			(layer "F.Fab")
			(hide yes)
			(effects
				(font
					(size 1.016 1.016)
					(thickness 0.1524)
				)
			)
		)
		(duplicate_pad_numbers_are_jumpers no)
		(fp_line
			(start 0.508 -0.9398)
			(end -0.508 -0.9398)
			(stroke
				(width 0.1524)
				(type default)
			)
			(layer "F.SilkS")
		)
		(fp_line
			(start -0.508 -0.9398)
			(end -0.508 0.9398)
			(stroke
				(width 0.1524)
				(type default)
			)
			(layer "F.SilkS")
		)
		(fp_rect
			(start -0.508 0.9398)
			(end 0.508 -0.9398)
			(stroke
				(width 0)
				(type default)
			)
			(fill no)
			(layer "F.CrtYd")
		)
		(fp_rect
			(start -0.508 0.9398)
			(end 0.508 -0.9398)
			(stroke
				(width 0)
				(type default)
			)
			(fill no)
			(layer "F.Fab")
		)
		(pad "1" smd custom
			(at 0 -0.4445 90)
			(size 0.1397 0.1397)
			(layers "F.Cu" "F.Mask" "F.Paste")
			(net "P1V8")
			(options
				(clearance outline)
				(anchor circle)
			)
			(primitives
				(gr_poly
					(pts
						(arc
							(start -0.1778 -0.2794)
							(mid -0.249642 -0.249642)
							(end -0.2794 -0.1778)
						)
						(arc
							(start -0.2794 0.1778)
							(mid -0.249642 0.249642)
							(end -0.1778 0.2794)
						)
						(arc
							(start 0.1778 0.2794)
							(mid 0.249642 0.249642)
							(end 0.2794 0.1778)
						)
						(arc
							(start 0.2794 -0.1778)
							(mid 0.249642 -0.249642)
							(end 0.1778 -0.2794)
						)
					)
					(width 0)
					(fill yes)
				)
			)
		)
		(pad "2" smd custom
			(at 0 0.4445 90)
			(size 0.1397 0.1397)
			(layers "F.Cu" "F.Mask" "F.Paste")
			(net "IOC_SCL_1")
			(options
				(clearance outline)
				(anchor circle)
			)
			(primitives
				(gr_poly
					(pts
						(arc
							(start -0.1778 -0.2794)
							(mid -0.249642 -0.249642)
							(end -0.2794 -0.1778)
						)
						(arc
							(start -0.2794 0.1778)
							(mid -0.249642 0.249642)
							(end -0.1778 0.2794)
						)
						(arc
							(start 0.1778 0.2794)
							(mid 0.249642 0.249642)
							(end 0.2794 0.1778)
						)
						(arc
							(start 0.2794 -0.1778)
							(mid 0.249642 -0.249642)
							(end 0.1778 -0.2794)
						)
					)
					(width 0)
					(fill yes)
				)
			)
		)
	)
)
